# S9S_MB_2U (Grand Teton) — schematic netlist excerpt (pin names and nets, part order shuffled) for the footprints in the layout excerpt that follows; sources: Cadence DE-HDL packaged netlist, KiCad conversion of 03242023_DA0F0TMBIJ0_F0T_Motherboard_J_brd_V01_OCP.brd

PC2143  Q_CAP  10UF 16V 10% X6S  pkg C0805  page 162 : A = P12V_OCP_V3_2 ; B = GND
PR3806  Q_RES  6.8K 1% EMPTY  pkg 0402LF  page 162 : A = P12V_OCP_UV_2 ; B = P12V_OCP_OV_2
PC177  Q_CAP  1UF 16V 10% X6S  pkg C0402  page 276 : A = SW_P12V_PVCCINFAON_CPU0_FLT ; B = GND

(kicad_pcb
	(version 20260206)
	(generator "pcbnew")
	(generator_version "10.0")
	(general
		(thickness 1.6)
		(legacy_teardrops no)
	)
	(paper "A4")
	(title_block
		(title "03242023_DA0F0TMBIJ0_F0T_Motherboard_J_brd_V01_OCP.brd")
		(comment 1 "Grand Teton / footprints 226-228 of 6105")
	)
	(layers
		(0 "F.Cu" signal "TOP")
		(4 "In1.Cu" signal "GND")
		(6 "In2.Cu" signal "IN1")
		(8 "In3.Cu" signal "GND1")
		(10 "In4.Cu" signal "IN2")
		(12 "In5.Cu" signal "GND2")
		(14 "In6.Cu" signal "IN3")
		(16 "In7.Cu" signal "GND3")
		(18 "In8.Cu" signal "VCC")
		(20 "In9.Cu" signal "VCC1")
		(22 "In10.Cu" signal "GND4")
		(24 "In11.Cu" signal "IN4")
		(26 "In12.Cu" signal "GND5")
		(28 "In13.Cu" signal "IN5")
		(30 "In14.Cu" signal "GND6")
		(32 "In15.Cu" signal "IN6")
		(34 "In16.Cu" signal "GND7")
		(2 "B.Cu" signal "BOTTOM")
		(9 "F.Adhes" user "F.Adhesive")
		(11 "B.Adhes" user "B.Adhesive")
		(13 "F.Paste" user "Package Geometry/Pastemask Top")
		(15 "B.Paste" user "Package Geometry/Pastemask Bottom")
		(5 "F.SilkS" user "Ref Des/Silkscreen Top")
		(7 "B.SilkS" user "Ref Des/Silkscreen Bottom")
		(1 "F.Mask" user "Board Geometry/Soldermask Top")
		(3 "B.Mask" user "Board Geometry/Soldermask Bottom")
		(17 "Dwgs.User" user "User.Drawings")
		(19 "Cmts.User" user "User.Comments")
		(21 "Eco1.User" user "User.Eco1")
		(23 "Eco2.User" user "User.Eco2")
		(25 "Edge.Cuts" user "Board Geometry/Outline")
		(27 "Margin" user)
		(31 "F.CrtYd" user "Package Geometry/Place Bound Top")
		(29 "B.CrtYd" user "Package Geometry/Place Bound Bottom")
		(35 "F.Fab" user "Ref Des/Assembly Top")
		(33 "B.Fab" user "Ref Des/Assembly Bottom")
	)
	(footprint ""
		(layer "F.Cu")
		(at 76.839318 -17.777968 -90)
		(property "Reference" "PR3806"
			(at 0 0 270)
			(layer "F.SilkS")
			(hide yes)
			(effects
				(font
					(size 1.27 1.27)
				)
			)
		)
		(property "Value" ""
			(at 0 0 270)
			(layer "F.Fab")
			(effects
				(font
					(size 1.27 1.27)
				)
			)
		)
		(duplicate_pad_numbers_are_jumpers no)
		(fp_line
			(start -0.7874 0.4064)
			(end -0.7874 -0.4064)
			(stroke
				(width 0.1524)
				(type default)
			)
			(layer "F.SilkS")
		)
		(fp_line
			(start 0.7874 0.4064)
			(end -0.7874 0.4064)
			(stroke
				(width 0.1524)
				(type default)
			)
			(layer "F.SilkS")
		)
		(fp_line
			(start -0.7874 -0.4064)
			(end 0.7874 -0.4064)
			(stroke
				(width 0.1524)
				(type default)
			)
			(layer "F.SilkS")
		)
		(fp_line
			(start 0.7874 -0.4064)
			(end 0.7874 0.4064)
			(stroke
				(width 0.1524)
				(type default)
			)
			(layer "F.SilkS")
		)
		(fp_line
			(start -0.67945 0.3048)
			(end -0.67945 -0.305054)
			(stroke
				(width 0.1)
				(type default)
			)
			(layer "F.Fab")
		)
		(fp_line
			(start -0.12065 0.3048)
			(end -0.67945 0.3048)
			(stroke
				(width 0.1)
				(type default)
			)
			(layer "F.Fab")
		)
		(fp_line
			(start 0.120396 0.3048)
			(end 0.120396 0.2794)
			(stroke
				(width 0.1)
				(type default)
			)
			(layer "F.Fab")
		)
		(fp_line
			(start 0.67945 0.3048)
			(end 0.120396 0.3048)
			(stroke
				(width 0.1)
				(type default)
			)
			(layer "F.Fab")
		)
		(fp_line
			(start -0.12065 0.2794)
			(end -0.12065 0.3048)
			(stroke
				(width 0.1)
				(type default)
			)
			(layer "F.Fab")
		)
		(fp_line
			(start 0.120396 0.2794)
			(end -0.12065 0.2794)
			(stroke
				(width 0.1)
				(type default)
			)
			(layer "F.Fab")
		)
		(fp_line
			(start -0.12065 -0.2794)
			(end 0.12065 -0.2794)
			(stroke
				(width 0.1)
				(type default)
			)
			(layer "F.Fab")
		)
		(fp_line
			(start 0.12065 -0.2794)
			(end 0.12065 -0.3048)
			(stroke
				(width 0.1)
				(type default)
			)
			(layer "F.Fab")
		)
		(fp_line
			(start 0.12065 -0.3048)
			(end 0.67945 -0.3048)
			(stroke
				(width 0.1)
				(type default)
			)
			(layer "F.Fab")
		)
		(fp_line
			(start 0.67945 -0.3048)
			(end 0.67945 0.3048)
			(stroke
				(width 0.1)
				(type default)
			)
			(layer "F.Fab")
		)
		(fp_line
			(start -0.67945 -0.305054)
			(end -0.12065 -0.305054)
			(stroke
				(width 0.1)
				(type default)
			)
			(layer "F.Fab")
		)
		(fp_line
			(start -0.12065 -0.305054)
			(end -0.12065 -0.2794)
			(stroke
				(width 0.1)
				(type default)
			)
			(layer "F.Fab")
		)
		(pad "1" smd circle
			(at -0.40005 0 270)
			(size 0 0)
			(layers "F.Cu" "F.Mask" "F.Paste")
			(net "P12V_OCP_UV_2")
		)
		(pad "2" smd circle
			(at 0.40005 0 270)
			(size 0 0)
			(layers "F.Cu" "F.Mask" "F.Paste")
			(net "P12V_OCP_OV_2")
		)
	)
	(footprint ""
		(layer "F.Cu")
		(at 422.022524 -149.239224 -90)
		(property "Reference" "PC177"
			(at 0 0 270)
			(layer "F.SilkS")
			(hide yes)
			(effects
				(font
					(size 1.27 1.27)
				)
			)
		)
		(property "Value" ""
			(at 0 0 270)
			(layer "F.Fab")
			(effects
				(font
					(size 1.27 1.27)
				)
			)
		)
		(duplicate_pad_numbers_are_jumpers no)
		(fp_line
			(start -0.7874 0.4064)
			(end -0.7874 -0.4064)
			(stroke
				(width 0.1524)
				(type default)
			)
			(layer "F.SilkS")
		)
		(fp_line
			(start 0.7874 0.4064)
			(end -0.7874 0.4064)
			(stroke
				(width 0.1524)
				(type default)
			)
			(layer "F.SilkS")
		)
		(fp_line
			(start -0.7874 -0.4064)
			(end 0.7874 -0.4064)
			(stroke
				(width 0.1524)
				(type default)
			)
			(layer "F.SilkS")
		)
		(fp_line
			(start 0.7874 -0.4064)
			(end 0.7874 0.4064)
			(stroke
				(width 0.1524)
				(type default)
			)
			(layer "F.SilkS")
		)
		(fp_line
			(start -0.67945 0.3048)
			(end -0.67945 -0.305054)
			(stroke
				(width 0.1)
				(type default)
			)
			(layer "F.Fab")
		)
		(fp_line
			(start -0.12065 0.3048)
			(end -0.67945 0.3048)
			(stroke
				(width 0.1)
				(type default)
			)
			(layer "F.Fab")
		)
		(fp_line
			(start 0.120396 0.3048)
			(end 0.120396 0.2794)
			(stroke
				(width 0.1)
				(type default)
			)
			(layer "F.Fab")
		)
		(fp_line
			(start 0.67945 0.3048)
			(end 0.120396 0.3048)
			(stroke
				(width 0.1)
				(type default)
			)
			(layer "F.Fab")
		)
		(fp_line
			(start -0.12065 0.2794)
			(end -0.12065 0.3048)
			(stroke
				(width 0.1)
				(type default)
			)
			(layer "F.Fab")
		)
		(fp_line
			(start 0.120396 0.2794)
			(end -0.12065 0.2794)
			(stroke
				(width 0.1)
				(type default)
			)
			(layer "F.Fab")
		)
		(fp_line
			(start -0.12065 -0.2794)
			(end 0.12065 -0.2794)
			(stroke
				(width 0.1)
				(type default)
			)
			(layer "F.Fab")
		)
		(fp_line
			(start 0.12065 -0.2794)
			(end 0.12065 -0.3048)
			(stroke
				(width 0.1)
				(type default)
			)
			(layer "F.Fab")
		)
		(fp_line
			(start 0.12065 -0.3048)
			(end 0.67945 -0.3048)
			(stroke
				(width 0.1)
				(type default)
			)
			(layer "F.Fab")
		)
		(fp_line
			(start 0.67945 -0.3048)
			(end 0.67945 0.3048)
			(stroke
				(width 0.1)
				(type default)
			)
			(layer "F.Fab")
		)
		(fp_line
			(start -0.67945 -0.305054)
			(end -0.12065 -0.305054)
			(stroke
				(width 0.1)
				(type default)
			)
			(layer "F.Fab")
		)
		(fp_line
			(start -0.12065 -0.305054)
			(end -0.12065 -0.2794)
			(stroke
				(width 0.1)
				(type default)
			)
			(layer "F.Fab")
		)
		(pad "1" smd circle
			(at -0.40005 0 270)
			(size 0 0)
			(layers "F.Cu" "F.Mask" "F.Paste")
			(net "SW_P12V_PVCCINFAON_CPU0_FLT")
		)
		(pad "2" smd circle
			(at 0.40005 0 270)
			(size 0 0)
			(layers "F.Cu" "F.Mask" "F.Paste")
			(net "GND")
		)
	)
	(footprint ""
		(layer "F.Cu")
		(at 65.828926 -20.04822 180)
		(property "Reference" "PC2143"
			(at 0 0 180)
			(layer "F.SilkS")
			(hide yes)
			(effects
				(font
					(size 1.27 1.27)
				)
			)
		)
		(property "Value" ""
			(at 0 0 180)
			(layer "F.Fab")
			(effects
				(font
					(size 1.27 1.27)
				)
			)
		)
		(duplicate_pad_numbers_are_jumpers no)
		(fp_line
			(start 1.524 0.762)
			(end -1.524 0.762)
			(stroke
				(width 0.1524)
				(type default)
			)
			(layer "F.SilkS")
		)
		(fp_line
			(start 1.524 -0.762)
			(end 1.524 0.762)
			(stroke
				(width 0.1524)
				(type default)
			)
			(layer "F.SilkS")
		)
		(fp_line
			(start -1.524 0.762)
			(end -1.524 -0.762)
			(stroke
				(width 0.1524)
				(type default)
			)
			(layer "F.SilkS")
		)
		(fp_line
			(start -1.524 -0.762)
			(end 1.524 -0.762)
			(stroke
				(width 0.1524)
				(type default)
			)
			(layer "F.SilkS")
		)
		(fp_line
			(start 1.1049 0.724916)
			(end 1.1049 -0.724916)
			(stroke
				(width 0.1)
				(type default)
			)
			(layer "F.Fab")
		)
		(fp_line
			(start 1.1049 -0.724916)
			(end -1.1049 -0.724916)
			(stroke
				(width 0.1)
				(type default)
			)
			(layer "F.Fab")
		)
		(fp_line
			(start -1.1049 0.724916)
			(end 1.1049 0.724916)
			(stroke
				(width 0.1)
				(type default)
			)
			(layer "F.Fab")
		)
		(fp_line
			(start -1.1049 -0.724916)
			(end -1.1049 0.724916)
			(stroke
				(width 0.1)
				(type default)
			)
			(layer "F.Fab")
		)
		(pad "1" smd rect
			(at -0.889 0)
			(size 1.016 1.27)
			(layers "F.Cu" "F.Mask" "F.Paste")
			(net "P12V_OCP_V3_2")
		)
		(pad "2" smd rect
			(at 0.889 0)
			(size 1.016 1.27)
			(layers "F.Cu" "F.Mask" "F.Paste")
			(net "GND")
		)
	)
)
